#ISCELL
  mstr_misc prelim *
  *
#ISCELL
  mstr_symbols design_note *
  *
#ISCELL
  mstr_symbols intel_corp_bpage *
  *
#ISCELL
  mstr_standard offpage *
  page39_i122
#ISCELL
  mstr_symbols vcc_core *
  page39_i123
#ISCELL
  mstr_symbols vcc_core *
  page39_i125
#ISCELL
  mstr_symbols vcc_core *
  page39_i126
#CELL
  chpset_lib skx_ext_b *
  page39_i127
#ISCELL
  mstr_symbols pvccio_cpu0 *
  page39_i23
#ISCELL
  mstr_standard offpage *
  page39_i33
#ISCELL
  mstr_standard offpage *
  page39_i34
#ISCELL
  mstr_standard offpage *
  page39_i35
#ISCELL
  mstr_standard offpage *
  page39_i36
#ISCELL
  mstr_standard offpage *
  page39_i37
#ISCELL
  mstr_standard offpage *
  page39_i38
#ISCELL
  mstr_standard offpage *
  page39_i39
#ISCELL
  mstr_standard offpage *
  page39_i40
